G04*
G04 #@! TF.GenerationSoftware,Altium Limited,Altium Designer,23.6.0 (18)*
G04*
G04 Layer_Physical_Order=2*
G04 Layer_Color=36540*
%FSLAX44Y44*%
%MOMM*%
G71*
G04*
G04 #@! TF.SameCoordinates,B62FFF2A-40BB-47C2-B022-6C0D6E2DF31E*
G04*
G04*
G04 #@! TF.FilePolarity,Positive*
G04*
G01*
G75*
%ADD65C,0.4064*%
%ADD66C,5.5000*%
G36*
X215922Y35578D02*
X214250D01*
X214052Y35539D01*
X213850Y35559D01*
X212875Y35463D01*
X212301Y35289D01*
X211714Y35172D01*
X209911Y34425D01*
X208588Y33541D01*
X207209Y32162D01*
X207209Y32162D01*
X206325Y30839D01*
X205961Y29959D01*
X176253D01*
X176193Y30570D01*
X176019Y31144D01*
X175902Y31731D01*
X175007Y33894D01*
X174123Y35217D01*
X172467Y36872D01*
X171144Y37757D01*
X171144Y37757D01*
X168981Y38652D01*
X168981Y38653D01*
X167421Y38963D01*
X165079D01*
X163519Y38653D01*
X163519Y38652D01*
X161356Y37757D01*
X160033Y36872D01*
X158377Y35217D01*
X157493Y33894D01*
X157493Y33894D01*
X156597Y31731D01*
X156481Y31144D01*
X156307Y30570D01*
X156247Y29959D01*
X36559D01*
X36302Y30343D01*
Y31657D01*
X35799Y32870D01*
X34870Y33799D01*
X34838Y33813D01*
Y35187D01*
X34870Y35201D01*
X35799Y36130D01*
X36302Y37343D01*
Y38657D01*
X35799Y39870D01*
X34870Y40799D01*
X34578Y40921D01*
Y42295D01*
X34750Y42367D01*
X35679Y43295D01*
X36182Y44509D01*
Y45823D01*
X35679Y47036D01*
X35135Y47581D01*
X34943Y48496D01*
X35185Y49160D01*
X35799Y49775D01*
X36302Y50988D01*
Y52302D01*
X35799Y53516D01*
X34870Y54444D01*
X33657Y54947D01*
X32343D01*
X31130Y54444D01*
X30201Y53516D01*
X29698Y52302D01*
Y50988D01*
X30201Y49775D01*
X30745Y49230D01*
X30937Y48315D01*
X30696Y47651D01*
X30081Y47036D01*
X29578Y45823D01*
Y44509D01*
X30081Y43295D01*
X31010Y42367D01*
X31302Y42245D01*
Y40871D01*
X31130Y40799D01*
X30201Y39870D01*
X29698Y38657D01*
Y37343D01*
X30201Y36130D01*
X31130Y35201D01*
X31162Y35187D01*
Y33813D01*
X31130Y33799D01*
X30201Y32870D01*
X29698Y31657D01*
Y30343D01*
X29441Y29959D01*
X14039D01*
X13675Y30838D01*
X12791Y32162D01*
X11412Y33541D01*
X11412Y33541D01*
X10088Y34425D01*
X10088Y34425D01*
X8286Y35172D01*
X7699Y35289D01*
X7125Y35463D01*
X6150Y35559D01*
X5948Y35539D01*
X5750Y35578D01*
X4078D01*
X4078Y415922D01*
X215922D01*
X215922Y35578D01*
D02*
G37*
%LPC*%
G36*
X181657Y378302D02*
X180343D01*
X179130Y377799D01*
X178201Y376870D01*
X177698Y375657D01*
Y374343D01*
X178201Y373130D01*
X179130Y372201D01*
X180343Y371698D01*
X181657D01*
X182870Y372201D01*
X183799Y373130D01*
X184302Y374343D01*
Y375657D01*
X183799Y376870D01*
X182870Y377799D01*
X181657Y378302D01*
D02*
G37*
G36*
X145657Y371302D02*
X144343D01*
X143130Y370799D01*
X142201Y369870D01*
X141698Y368657D01*
Y367343D01*
X142201Y366130D01*
X143130Y365201D01*
X144343Y364698D01*
X145657D01*
X146870Y365201D01*
X147799Y366130D01*
X148302Y367343D01*
Y368657D01*
X147799Y369870D01*
X146870Y370799D01*
X145657Y371302D01*
D02*
G37*
G36*
X135657D02*
X134343D01*
X133130Y370799D01*
X132201Y369870D01*
X131698Y368657D01*
Y367343D01*
X132201Y366130D01*
X133130Y365201D01*
X134343Y364698D01*
X135657D01*
X136870Y365201D01*
X137799Y366130D01*
X138302Y367343D01*
Y368657D01*
X137799Y369870D01*
X136870Y370799D01*
X135657Y371302D01*
D02*
G37*
G36*
X133187Y322302D02*
X131873D01*
X130659Y321799D01*
X130328Y321467D01*
X129498Y321001D01*
X128668Y321467D01*
X128336Y321799D01*
X127123Y322302D01*
X125809D01*
X124595Y321799D01*
X123666Y320871D01*
X123164Y319657D01*
Y318343D01*
X123666Y317130D01*
X124595Y316201D01*
X125809Y315698D01*
X127123D01*
X128336Y316201D01*
X128668Y316533D01*
X129498Y316999D01*
X130328Y316533D01*
X130659Y316201D01*
X131873Y315698D01*
X133187D01*
X134400Y316201D01*
X135329Y317130D01*
X135832Y318343D01*
Y319657D01*
X135329Y320871D01*
X134400Y321799D01*
X133187Y322302D01*
D02*
G37*
G36*
X159657Y325302D02*
X158343D01*
X157130Y324799D01*
X156201Y323870D01*
X155698Y322657D01*
Y321343D01*
X156201Y320130D01*
X157130Y319201D01*
X158343Y318698D01*
X159657D01*
X160870Y319201D01*
X161799Y320130D01*
X162302Y321343D01*
Y322657D01*
X161799Y323870D01*
X160870Y324799D01*
X159657Y325302D01*
D02*
G37*
G36*
X83657Y320302D02*
X82343D01*
X81130Y319799D01*
X80201Y318870D01*
X79698Y317657D01*
Y316343D01*
X80201Y315130D01*
X81130Y314201D01*
X82343Y313698D01*
X83657D01*
X84870Y314201D01*
X85799Y315130D01*
X86302Y316343D01*
Y317657D01*
X85799Y318870D01*
X84870Y319799D01*
X83657Y320302D01*
D02*
G37*
G36*
X50657Y164302D02*
X49343D01*
X48130Y163799D01*
X47201Y162870D01*
X46698Y161657D01*
Y160343D01*
X47201Y159130D01*
X48130Y158201D01*
X49343Y157698D01*
X50657D01*
X51870Y158201D01*
X52799Y159130D01*
X53302Y160343D01*
Y161657D01*
X52799Y162870D01*
X51870Y163799D01*
X50657Y164302D01*
D02*
G37*
G36*
X39657Y150302D02*
X38343D01*
X37130Y149799D01*
X36201Y148870D01*
X35698Y147657D01*
Y146343D01*
X36201Y145130D01*
X37130Y144201D01*
X38343Y143698D01*
X39657D01*
X40870Y144201D01*
X41799Y145130D01*
X42302Y146343D01*
Y147657D01*
X41799Y148870D01*
X40870Y149799D01*
X39657Y150302D01*
D02*
G37*
G36*
X159657Y155302D02*
X158343D01*
X157130Y154799D01*
X156201Y153870D01*
X155698Y152657D01*
Y151343D01*
X156201Y150130D01*
X156795Y149535D01*
X157008Y148750D01*
X156795Y147965D01*
X156201Y147370D01*
X155698Y146157D01*
Y144843D01*
X156201Y143630D01*
X156563Y143267D01*
X156993Y142437D01*
X156563Y141608D01*
X156201Y141245D01*
X155698Y140031D01*
Y138718D01*
X156201Y137504D01*
X157130Y136575D01*
X158343Y136073D01*
X159657D01*
X160870Y136575D01*
X161799Y137504D01*
X162302Y138718D01*
Y140031D01*
X161799Y141245D01*
X161437Y141608D01*
X161007Y142437D01*
X161437Y143267D01*
X161799Y143630D01*
X162302Y144843D01*
Y146157D01*
X161799Y147370D01*
X161205Y147965D01*
X160993Y148750D01*
X161205Y149535D01*
X161799Y150130D01*
X162302Y151343D01*
Y152657D01*
X161799Y153870D01*
X160870Y154799D01*
X159657Y155302D01*
D02*
G37*
G36*
X125657Y140052D02*
X124343D01*
X123130Y139549D01*
X122201Y138620D01*
X121698Y137407D01*
Y136093D01*
X122201Y134880D01*
X123130Y133951D01*
X124343Y133448D01*
X125657D01*
X126870Y133951D01*
X127799Y134880D01*
X128302Y136093D01*
Y137407D01*
X127799Y138620D01*
X126870Y139549D01*
X125657Y140052D01*
D02*
G37*
G36*
X94657D02*
X93343D01*
X92130Y139549D01*
X91201Y138620D01*
X90698Y137407D01*
Y136093D01*
X91201Y134880D01*
X92130Y133951D01*
X93343Y133448D01*
X94657D01*
X95870Y133951D01*
X96799Y134880D01*
X97302Y136093D01*
Y137407D01*
X96799Y138620D01*
X95870Y139549D01*
X94657Y140052D01*
D02*
G37*
G36*
X117657Y124302D02*
X116343D01*
X115130Y123799D01*
X114201Y122870D01*
X113698Y121657D01*
Y120343D01*
X114201Y119130D01*
X115130Y118201D01*
X116343Y117698D01*
X117657D01*
X118870Y118201D01*
X119799Y119130D01*
X120302Y120343D01*
Y121657D01*
X119799Y122870D01*
X118870Y123799D01*
X117657Y124302D01*
D02*
G37*
G36*
X102657Y122302D02*
X101343D01*
X100130Y121799D01*
X99201Y120870D01*
X98698Y119657D01*
Y118343D01*
X99201Y117130D01*
X100130Y116201D01*
X101343Y115698D01*
X102657D01*
X103870Y116201D01*
X104799Y117130D01*
X105302Y118343D01*
Y119657D01*
X104799Y120870D01*
X103870Y121799D01*
X102657Y122302D01*
D02*
G37*
G36*
X50657Y118302D02*
X49343D01*
X48130Y117799D01*
X47201Y116870D01*
X46698Y115657D01*
Y114343D01*
X47201Y113130D01*
X48130Y112201D01*
X49343Y111698D01*
X50657D01*
X51870Y112201D01*
X52799Y113130D01*
X53302Y114343D01*
Y115657D01*
X52799Y116870D01*
X51870Y117799D01*
X50657Y118302D01*
D02*
G37*
G36*
X40657Y117302D02*
X39343D01*
X38130Y116799D01*
X37201Y115870D01*
X36698Y114657D01*
Y113343D01*
X37201Y112130D01*
X38130Y111201D01*
X39343Y110698D01*
X40657D01*
X41870Y111201D01*
X42799Y112130D01*
X43302Y113343D01*
Y114657D01*
X42799Y115870D01*
X41870Y116799D01*
X40657Y117302D01*
D02*
G37*
G36*
X78657Y89302D02*
X77343D01*
X76130Y88799D01*
X75201Y87870D01*
X74698Y86657D01*
Y85343D01*
X75201Y84130D01*
X76130Y83201D01*
X77343Y82698D01*
X78657D01*
X79870Y83201D01*
X80799Y84130D01*
X81302Y85343D01*
Y86657D01*
X80799Y87870D01*
X79870Y88799D01*
X78657Y89302D01*
D02*
G37*
G36*
X38657Y87302D02*
X37343D01*
X36130Y86799D01*
X35201Y85870D01*
X34698Y84657D01*
Y83343D01*
X35201Y82130D01*
X36130Y81201D01*
X37343Y80698D01*
X38657D01*
X39870Y81201D01*
X40799Y82130D01*
X41302Y83343D01*
Y84657D01*
X40799Y85870D01*
X39870Y86799D01*
X38657Y87302D01*
D02*
G37*
G36*
X112657Y80302D02*
X111343D01*
X110130Y79799D01*
X109201Y78870D01*
X108698Y77657D01*
Y76343D01*
X109201Y75130D01*
X110130Y74201D01*
X111343Y73698D01*
X112657D01*
X113870Y74201D01*
X114799Y75130D01*
X115302Y76343D01*
Y77657D01*
X114799Y78870D01*
X113870Y79799D01*
X112657Y80302D01*
D02*
G37*
G36*
X187752Y67302D02*
X186439D01*
X185225Y66799D01*
X184893Y66467D01*
X184063Y66001D01*
X183234Y66467D01*
X182902Y66799D01*
X181688Y67302D01*
X180375D01*
X179161Y66799D01*
X178232Y65870D01*
X177729Y64657D01*
Y63343D01*
X178232Y62130D01*
X179161Y61201D01*
X180375Y60698D01*
X181688D01*
X182902Y61201D01*
X183234Y61533D01*
X184063Y61999D01*
X184893Y61533D01*
X185225Y61201D01*
X186439Y60698D01*
X187752D01*
X188966Y61201D01*
X189895Y62130D01*
X190397Y63343D01*
Y64657D01*
X189895Y65870D01*
X188966Y66799D01*
X187752Y67302D01*
D02*
G37*
G36*
X80657Y52302D02*
X79343D01*
X78130Y51799D01*
X77201Y50870D01*
X76698Y49657D01*
Y48343D01*
X77201Y47130D01*
X78130Y46201D01*
X79343Y45698D01*
X80657D01*
X81870Y46201D01*
X82799Y47130D01*
X83302Y48343D01*
Y49657D01*
X82799Y50870D01*
X81870Y51799D01*
X80657Y52302D01*
D02*
G37*
G36*
X45657D02*
X44343D01*
X43130Y51799D01*
X42201Y50870D01*
X41698Y49657D01*
Y48343D01*
X42201Y47130D01*
X43130Y46201D01*
X44343Y45698D01*
X45657D01*
X46870Y46201D01*
X47799Y47130D01*
X48302Y48343D01*
Y49657D01*
X47799Y50870D01*
X46870Y51799D01*
X45657Y52302D01*
D02*
G37*
G36*
X118657Y50302D02*
X117343D01*
X116130Y49799D01*
X115201Y48870D01*
X114698Y47657D01*
Y46343D01*
X115201Y45130D01*
X116130Y44201D01*
X117343Y43698D01*
X118657D01*
X119870Y44201D01*
X120799Y45130D01*
X121302Y46343D01*
Y47657D01*
X120799Y48870D01*
X119870Y49799D01*
X118657Y50302D01*
D02*
G37*
G36*
X204114Y51557D02*
X202801D01*
X201587Y51055D01*
X200658Y50126D01*
X200156Y48912D01*
Y47599D01*
X200658Y46385D01*
X201587Y45456D01*
X202801Y44953D01*
X204114D01*
X205328Y45456D01*
X206257Y46385D01*
X206514Y47006D01*
X206607Y47022D01*
X207836Y46880D01*
X208201Y46000D01*
X209130Y45071D01*
X210343Y44568D01*
Y43302D01*
X209130Y42799D01*
X208201Y41870D01*
X206914D01*
X205985Y42799D01*
X204771Y43302D01*
X203458D01*
X202244Y42799D01*
X201315Y41870D01*
X200812Y40657D01*
Y39343D01*
X201315Y38130D01*
X202244Y37201D01*
X203458Y36698D01*
X204771D01*
X205985Y37201D01*
X206914Y38129D01*
X208201D01*
X209130Y37201D01*
X210343Y36698D01*
X211657D01*
X212870Y37201D01*
X213799Y38130D01*
X214302Y39343D01*
Y40657D01*
X213799Y41870D01*
X212870Y42799D01*
X211657Y43302D01*
Y44568D01*
X212870Y45071D01*
X213799Y46000D01*
X214302Y47214D01*
Y48527D01*
X213799Y49741D01*
X212870Y50670D01*
X211657Y51172D01*
X210343D01*
X209130Y50670D01*
X208201Y49741D01*
X207943Y49120D01*
X207851Y49104D01*
X206621Y49246D01*
X206257Y50126D01*
X205328Y51055D01*
X204114Y51557D01*
D02*
G37*
G36*
X56657Y48302D02*
X55343D01*
X54130Y47799D01*
X53201Y46870D01*
X52698Y45657D01*
Y44343D01*
X53201Y43130D01*
X54130Y42201D01*
X55343Y41698D01*
X56657D01*
X57870Y42201D01*
X58799Y43130D01*
X59302Y44343D01*
Y45657D01*
X58799Y46870D01*
X57870Y47799D01*
X56657Y48302D01*
D02*
G37*
%LPD*%
D65*
X69468Y121045D02*
D03*
X40000Y114000D02*
D03*
X50000Y115000D02*
D03*
X39000Y147000D02*
D03*
X118000Y47000D02*
D03*
X200000Y78350D02*
D03*
X207794Y79007D02*
D03*
X203112Y61996D02*
D03*
X211343Y71000D02*
D03*
X212000Y61000D02*
D03*
X63000Y38000D02*
D03*
X193000Y37000D02*
D03*
X208000Y193000D02*
D03*
X205000Y239000D02*
D03*
X206000Y215000D02*
D03*
Y259000D02*
D03*
Y268000D02*
D03*
Y276000D02*
D03*
X213640Y410220D02*
D03*
X209830Y402600D02*
D03*
X213640Y394980D02*
D03*
X209830Y387360D02*
D03*
X206020Y410220D02*
D03*
X202210Y402600D02*
D03*
X206020Y394980D02*
D03*
X202210Y387360D02*
D03*
Y174000D02*
D03*
Y158760D02*
D03*
Y143520D02*
D03*
X198400Y410220D02*
D03*
X194590Y402600D02*
D03*
X198400Y394980D02*
D03*
X194590Y387360D02*
D03*
X190780Y410220D02*
D03*
X186970Y402600D02*
D03*
X190780Y394980D02*
D03*
X186970Y387360D02*
D03*
X183160Y410220D02*
D03*
X179350Y402600D02*
D03*
X183160Y394980D02*
D03*
X179350Y387360D02*
D03*
X175540Y410220D02*
D03*
X171730Y402600D02*
D03*
X175540Y394980D02*
D03*
X171730Y387360D02*
D03*
X167920Y410220D02*
D03*
X164110Y402600D02*
D03*
X167920Y394980D02*
D03*
X164110Y387360D02*
D03*
X160300Y410220D02*
D03*
X156490Y402600D02*
D03*
X160300Y394980D02*
D03*
X156490Y387360D02*
D03*
X152680Y410220D02*
D03*
X148870Y402600D02*
D03*
X152680Y394980D02*
D03*
X148870Y387360D02*
D03*
X145060Y410220D02*
D03*
X141250Y402600D02*
D03*
X145060Y394980D02*
D03*
X141250Y387360D02*
D03*
X137440Y394980D02*
D03*
X133630Y387360D02*
D03*
X126010D02*
D03*
X110770Y372120D02*
D03*
X106960Y379740D02*
D03*
X103150Y372120D02*
D03*
X106960Y364500D02*
D03*
X103150Y341640D02*
D03*
X95530Y387360D02*
D03*
X99340Y379740D02*
D03*
X95530Y372120D02*
D03*
X99340Y364500D02*
D03*
X95530Y341640D02*
D03*
Y311160D02*
D03*
Y295920D02*
D03*
Y280680D02*
D03*
X87910Y387360D02*
D03*
X91720Y379740D02*
D03*
X87910Y372120D02*
D03*
X91720Y364500D02*
D03*
X87910Y341640D02*
D03*
Y326400D02*
D03*
X91720Y303540D02*
D03*
Y288300D02*
D03*
X87910Y280680D02*
D03*
X91720Y273060D02*
D03*
X87910Y265440D02*
D03*
X80290Y402600D02*
D03*
X84100Y394980D02*
D03*
X80290Y387360D02*
D03*
X84100Y379740D02*
D03*
X80290Y372120D02*
D03*
X84100Y364500D02*
D03*
Y334020D02*
D03*
X80290Y326400D02*
D03*
Y280680D02*
D03*
X84100Y273060D02*
D03*
X80290Y265440D02*
D03*
X76480Y410220D02*
D03*
X72670Y402600D02*
D03*
X76480Y394980D02*
D03*
X72670Y387360D02*
D03*
X76480Y379740D02*
D03*
X72670Y372120D02*
D03*
X76480Y334020D02*
D03*
X72670Y326400D02*
D03*
X76480Y318780D02*
D03*
Y273060D02*
D03*
X72670Y265440D02*
D03*
X68860Y410220D02*
D03*
X65050Y402600D02*
D03*
X68860Y394980D02*
D03*
X65050Y387360D02*
D03*
X68860Y379740D02*
D03*
X65050Y372120D02*
D03*
X68860Y334020D02*
D03*
X65050Y326400D02*
D03*
X68860Y318780D02*
D03*
Y273060D02*
D03*
X65050Y265440D02*
D03*
X61240Y379740D02*
D03*
X57430Y372120D02*
D03*
X61240Y334020D02*
D03*
X57430Y326400D02*
D03*
Y280680D02*
D03*
X53620Y379740D02*
D03*
X49810Y372120D02*
D03*
Y280680D02*
D03*
X42190D02*
D03*
X46000Y273060D02*
D03*
X42190Y265440D02*
D03*
X38380Y410220D02*
D03*
X34570Y402600D02*
D03*
Y280680D02*
D03*
X38380Y273060D02*
D03*
X34570Y265440D02*
D03*
X30760Y410220D02*
D03*
X26950Y326400D02*
D03*
X30760Y318780D02*
D03*
X26950Y311160D02*
D03*
X30760Y303540D02*
D03*
X26950Y295920D02*
D03*
X30760Y288300D02*
D03*
X26950Y280680D02*
D03*
X30760Y273060D02*
D03*
X26950Y265440D02*
D03*
X19330Y372120D02*
D03*
X23140Y364500D02*
D03*
X19330Y356880D02*
D03*
X23140Y349260D02*
D03*
X19330Y341640D02*
D03*
X23140Y334020D02*
D03*
X19330Y326400D02*
D03*
X23140Y318780D02*
D03*
X19330Y311160D02*
D03*
X23140Y303540D02*
D03*
X19330Y295920D02*
D03*
X23140Y288300D02*
D03*
X19330Y280680D02*
D03*
X23140Y273060D02*
D03*
X19330Y265440D02*
D03*
Y250200D02*
D03*
Y234960D02*
D03*
Y219720D02*
D03*
Y204480D02*
D03*
Y189240D02*
D03*
Y174000D02*
D03*
Y158760D02*
D03*
Y143520D02*
D03*
Y128280D02*
D03*
Y113040D02*
D03*
Y97800D02*
D03*
Y82560D02*
D03*
Y67320D02*
D03*
X15520Y379740D02*
D03*
X11710Y372120D02*
D03*
X15520Y364500D02*
D03*
X11710Y356880D02*
D03*
X15520Y349260D02*
D03*
X11710Y341640D02*
D03*
X15520Y334020D02*
D03*
X11710Y326400D02*
D03*
X15520Y318780D02*
D03*
X11710Y311160D02*
D03*
X15520Y303540D02*
D03*
X11710Y295920D02*
D03*
X15520Y288300D02*
D03*
X11710Y280680D02*
D03*
X15520Y273060D02*
D03*
X11710Y265440D02*
D03*
X15520Y257820D02*
D03*
X11710Y250200D02*
D03*
X15520Y242580D02*
D03*
X11710Y234960D02*
D03*
X15520Y227340D02*
D03*
X11710Y219720D02*
D03*
X15520Y212100D02*
D03*
X11710Y204480D02*
D03*
X15520Y196860D02*
D03*
X11710Y189240D02*
D03*
X15520Y181620D02*
D03*
X11710Y174000D02*
D03*
X15520Y166380D02*
D03*
X11710Y158760D02*
D03*
X15520Y151140D02*
D03*
X11710Y143520D02*
D03*
X15520Y135900D02*
D03*
X11710Y128280D02*
D03*
X15520Y120660D02*
D03*
X11710Y113040D02*
D03*
X15520Y105420D02*
D03*
X11710Y97800D02*
D03*
X15520Y90180D02*
D03*
X11710Y82560D02*
D03*
X15520Y74940D02*
D03*
X11710Y67320D02*
D03*
X15520Y59700D02*
D03*
X32151Y339810D02*
D03*
X31576Y332800D02*
D03*
X35076Y326800D02*
D03*
X38651Y320417D02*
D03*
X43408Y314602D02*
D03*
X55998Y314097D02*
D03*
X54580Y320095D02*
D03*
X50238Y325800D02*
D03*
X47228Y332057D02*
D03*
X46887Y338234D02*
D03*
X46651Y344528D02*
D03*
X41962Y367714D02*
D03*
X39820Y373823D02*
D03*
X31485Y353188D02*
D03*
X30909Y359800D02*
D03*
X29145Y365800D02*
D03*
X33000Y393477D02*
D03*
X23000Y383750D02*
D03*
X24523Y377500D02*
D03*
X28054Y371915D02*
D03*
X31719Y347000D02*
D03*
X46267Y350969D02*
D03*
X43782Y379467D02*
D03*
X41000Y393477D02*
D03*
X9000Y395000D02*
D03*
Y408000D02*
D03*
X62000Y394000D02*
D03*
X73000Y38000D02*
D03*
X187096Y64000D02*
D03*
X181031D02*
D03*
X78000Y86000D02*
D03*
X132530Y319000D02*
D03*
X126466D02*
D03*
X112000Y77000D02*
D03*
X106000Y106000D02*
D03*
X117000Y121000D02*
D03*
X102000Y119000D02*
D03*
X125000Y136750D02*
D03*
X94000D02*
D03*
X38000Y84000D02*
D03*
X83000Y317000D02*
D03*
X159000Y322000D02*
D03*
X50000Y161000D02*
D03*
X190000Y354000D02*
D03*
X177000Y340000D02*
D03*
X181000Y375000D02*
D03*
X145000Y368000D02*
D03*
X135000D02*
D03*
X95000Y334000D02*
D03*
X79000Y360000D02*
D03*
X39010Y160198D02*
D03*
X64425Y314602D02*
D03*
X36000Y314802D02*
D03*
X199000Y90000D02*
D03*
Y101000D02*
D03*
X198000Y117000D02*
D03*
Y126000D02*
D03*
X188000Y136000D02*
D03*
Y148000D02*
D03*
Y160000D02*
D03*
X159000Y152000D02*
D03*
Y145500D02*
D03*
Y139375D02*
D03*
X176000Y44000D02*
D03*
X195873Y44688D02*
D03*
X196187Y51172D02*
D03*
X111000Y35000D02*
D03*
X204114Y40000D02*
D03*
X203458Y48255D02*
D03*
X211000Y40000D02*
D03*
Y47870D02*
D03*
X152000Y36000D02*
D03*
X137000D02*
D03*
X123000Y35000D02*
D03*
X93000Y34000D02*
D03*
X33000Y31000D02*
D03*
Y38000D02*
D03*
X32880Y45166D02*
D03*
X33000Y51645D02*
D03*
X15000Y50312D02*
D03*
X12791Y42000D02*
D03*
X6395Y41971D02*
D03*
X6826Y50312D02*
D03*
X80000Y49000D02*
D03*
X45000D02*
D03*
X56000Y45000D02*
D03*
D66*
X110000Y420000D02*
D03*
M02*
